# S9S_MB_2U (Grand Teton) — schematic netlist excerpt (pin names and nets, part order shuffled) for the footprints in the layout excerpt that follows; sources: Cadence DE-HDL packaged netlist, KiCad conversion of 03242023_DA0F0TMBIJ0_F0T_Motherboard_J_brd_V01_OCP.brd

PC1351  Q_CAP  0.1UF 25V 10% X7R  pkg 0402  page 272 : A = GND ; B = PVCCIN_CPU0_VREF
R4514  Q_RES  4.7K 1% EMPTY  pkg 0402LF  page 212 : A = CLK_GEN2_GPU_FPGA_OE_R2_N ; B = GND

(kicad_pcb
	(version 20260206)
	(generator "pcbnew")
	(generator_version "10.0")
	(general
		(thickness 1.6)
		(legacy_teardrops no)
	)
	(paper "A4")
	(title_block
		(title "03242023_DA0F0TMBIJ0_F0T_Motherboard_J_brd_V01_OCP.brd")
		(comment 1 "Grand Teton / footprints 3202-3203 of 6105")
	)
	(layers
		(0 "F.Cu" signal "TOP")
		(4 "In1.Cu" signal "GND")
		(6 "In2.Cu" signal "IN1")
		(8 "In3.Cu" signal "GND1")
		(10 "In4.Cu" signal "IN2")
		(12 "In5.Cu" signal "GND2")
		(14 "In6.Cu" signal "IN3")
		(16 "In7.Cu" signal "GND3")
		(18 "In8.Cu" signal "VCC")
		(20 "In9.Cu" signal "VCC1")
		(22 "In10.Cu" signal "GND4")
		(24 "In11.Cu" signal "IN4")
		(26 "In12.Cu" signal "GND5")
		(28 "In13.Cu" signal "IN5")
		(30 "In14.Cu" signal "GND6")
		(32 "In15.Cu" signal "IN6")
		(34 "In16.Cu" signal "GND7")
		(2 "B.Cu" signal "BOTTOM")
		(9 "F.Adhes" user "F.Adhesive")
		(11 "B.Adhes" user "B.Adhesive")
		(13 "F.Paste" user "Package Geometry/Pastemask Top")
		(15 "B.Paste" user "Package Geometry/Pastemask Bottom")
		(5 "F.SilkS" user "Ref Des/Silkscreen Top")
		(7 "B.SilkS" user "Ref Des/Silkscreen Bottom")
		(1 "F.Mask" user "Board Geometry/Soldermask Top")
		(3 "B.Mask" user "Board Geometry/Soldermask Bottom")
		(17 "Dwgs.User" user "User.Drawings")
		(19 "Cmts.User" user "User.Comments")
		(21 "Eco1.User" user "User.Eco1")
		(23 "Eco2.User" user "User.Eco2")
		(25 "Edge.Cuts" user "Board Geometry/Outline")
		(27 "Margin" user)
		(31 "F.CrtYd" user "Package Geometry/Place Bound Top")
		(29 "B.CrtYd" user "Package Geometry/Place Bound Bottom")
		(35 "F.Fab" user "Ref Des/Assembly Top")
		(33 "B.Fab" user "Ref Des/Assembly Bottom")
	)
	(footprint ""
		(layer "F.Cu")
		(at 113.882424 -37.01034 180)
		(property "Reference" "R4514"
			(at 0 0 180)
			(layer "F.SilkS")
			(hide yes)
			(effects
				(font
					(size 1.27 1.27)
				)
			)
		)
		(property "Value" ""
			(at 0 0 180)
			(layer "F.Fab")
			(effects
				(font
					(size 1.27 1.27)
				)
			)
		)
		(duplicate_pad_numbers_are_jumpers no)
		(fp_line
			(start 0.7874 0.4064)
			(end -0.7874 0.4064)
			(stroke
				(width 0.1524)
				(type default)
			)
			(layer "F.SilkS")
		)
		(fp_line
			(start 0.7874 -0.4064)
			(end 0.7874 0.4064)
			(stroke
				(width 0.1524)
				(type default)
			)
			(layer "F.SilkS")
		)
		(fp_line
			(start -0.7874 0.4064)
			(end -0.7874 -0.4064)
			(stroke
				(width 0.1524)
				(type default)
			)
			(layer "F.SilkS")
		)
		(fp_line
			(start -0.7874 -0.4064)
			(end 0.7874 -0.4064)
			(stroke
				(width 0.1524)
				(type default)
			)
			(layer "F.SilkS")
		)
		(fp_line
			(start 0.67945 0.3048)
			(end 0.120396 0.3048)
			(stroke
				(width 0.1)
				(type default)
			)
			(layer "F.Fab")
		)
		(fp_line
			(start 0.67945 -0.3048)
			(end 0.67945 0.3048)
			(stroke
				(width 0.1)
				(type default)
			)
			(layer "F.Fab")
		)
		(fp_line
			(start 0.12065 -0.2794)
			(end 0.12065 -0.3048)
			(stroke
				(width 0.1)
				(type default)
			)
			(layer "F.Fab")
		)
		(fp_line
			(start 0.12065 -0.3048)
			(end 0.67945 -0.3048)
			(stroke
				(width 0.1)
				(type default)
			)
			(layer "F.Fab")
		)
		(fp_line
			(start 0.120396 0.3048)
			(end 0.120396 0.2794)
			(stroke
				(width 0.1)
				(type default)
			)
			(layer "F.Fab")
		)
		(fp_line
			(start 0.120396 0.2794)
			(end -0.12065 0.2794)
			(stroke
				(width 0.1)
				(type default)
			)
			(layer "F.Fab")
		)
		(fp_line
			(start -0.12065 0.3048)
			(end -0.67945 0.3048)
			(stroke
				(width 0.1)
				(type default)
			)
			(layer "F.Fab")
		)
		(fp_line
			(start -0.12065 0.2794)
			(end -0.12065 0.3048)
			(stroke
				(width 0.1)
				(type default)
			)
			(layer "F.Fab")
		)
		(fp_line
			(start -0.12065 -0.2794)
			(end 0.12065 -0.2794)
			(stroke
				(width 0.1)
				(type default)
			)
			(layer "F.Fab")
		)
		(fp_line
			(start -0.12065 -0.305054)
			(end -0.12065 -0.2794)
			(stroke
				(width 0.1)
				(type default)
			)
			(layer "F.Fab")
		)
		(fp_line
			(start -0.67945 0.3048)
			(end -0.67945 -0.305054)
			(stroke
				(width 0.1)
				(type default)
			)
			(layer "F.Fab")
		)
		(fp_line
			(start -0.67945 -0.305054)
			(end -0.12065 -0.305054)
			(stroke
				(width 0.1)
				(type default)
			)
			(layer "F.Fab")
		)
		(pad "1" smd circle
			(at -0.40005 0 180)
			(size 0 0)
			(layers "F.Cu" "F.Mask" "F.Paste")
			(net "CLK_GEN2_GPU_FPGA_OE_R2_N")
		)
		(pad "2" smd circle
			(at 0.40005 0 180)
			(size 0 0)
			(layers "F.Cu" "F.Mask" "F.Paste")
			(net "GND")
		)
	)
	(footprint ""
		(layer "F.Cu")
		(at 423.096436 -366.66932 -90)
		(property "Reference" "PC1351"
			(at 0 0 270)
			(layer "F.SilkS")
			(hide yes)
			(effects
				(font
					(size 1.27 1.27)
				)
			)
		)
		(property "Value" ""
			(at 0 0 270)
			(layer "F.Fab")
			(effects
				(font
					(size 1.27 1.27)
				)
			)
		)
		(duplicate_pad_numbers_are_jumpers no)
		(fp_line
			(start -0.7874 0.4064)
			(end -0.7874 -0.4064)
			(stroke
				(width 0.1524)
				(type default)
			)
			(layer "F.SilkS")
		)
		(fp_line
			(start 0.7874 0.4064)
			(end -0.7874 0.4064)
			(stroke
				(width 0.1524)
				(type default)
			)
			(layer "F.SilkS")
		)
		(fp_line
			(start -0.7874 -0.4064)
			(end 0.7874 -0.4064)
			(stroke
				(width 0.1524)
				(type default)
			)
			(layer "F.SilkS")
		)
		(fp_line
			(start 0.7874 -0.4064)
			(end 0.7874 0.4064)
			(stroke
				(width 0.1524)
				(type default)
			)
			(layer "F.SilkS")
		)
		(fp_line
			(start -0.67945 0.3048)
			(end -0.67945 -0.305054)
			(stroke
				(width 0.1)
				(type default)
			)
			(layer "F.Fab")
		)
		(fp_line
			(start -0.12065 0.3048)
			(end -0.67945 0.3048)
			(stroke
				(width 0.1)
				(type default)
			)
			(layer "F.Fab")
		)
		(fp_line
			(start 0.120396 0.3048)
			(end 0.120396 0.2794)
			(stroke
				(width 0.1)
				(type default)
			)
			(layer "F.Fab")
		)
		(fp_line
			(start 0.67945 0.3048)
			(end 0.120396 0.3048)
			(stroke
				(width 0.1)
				(type default)
			)
			(layer "F.Fab")
		)
		(fp_line
			(start -0.12065 0.2794)
			(end -0.12065 0.3048)
			(stroke
				(width 0.1)
				(type default)
			)
			(layer "F.Fab")
		)
		(fp_line
			(start 0.120396 0.2794)
			(end -0.12065 0.2794)
			(stroke
				(width 0.1)
				(type default)
			)
			(layer "F.Fab")
		)
		(fp_line
			(start -0.12065 -0.2794)
			(end 0.12065 -0.2794)
			(stroke
				(width 0.1)
				(type default)
			)
			(layer "F.Fab")
		)
		(fp_line
			(start 0.12065 -0.2794)
			(end 0.12065 -0.3048)
			(stroke
				(width 0.1)
				(type default)
			)
			(layer "F.Fab")
		)
		(fp_line
			(start 0.12065 -0.3048)
			(end 0.67945 -0.3048)
			(stroke
				(width 0.1)
				(type default)
			)
			(layer "F.Fab")
		)
		(fp_line
			(start 0.67945 -0.3048)
			(end 0.67945 0.3048)
			(stroke
				(width 0.1)
				(type default)
			)
			(layer "F.Fab")
		)
		(fp_line
			(start -0.67945 -0.305054)
			(end -0.12065 -0.305054)
			(stroke
				(width 0.1)
				(type default)
			)
			(layer "F.Fab")
		)
		(fp_line
			(start -0.12065 -0.305054)
			(end -0.12065 -0.2794)
			(stroke
				(width 0.1)
				(type default)
			)
			(layer "F.Fab")
		)
		(pad "1" smd circle
			(at -0.40005 0 270)
			(size 0 0)
			(layers "F.Cu" "F.Mask" "F.Paste")
			(net "GND")
		)
		(pad "2" smd circle
			(at 0.40005 0 270)
			(size 0 0)
			(layers "F.Cu" "F.Mask" "F.Paste")
			(net "PVCCIN_CPU0_VREF")
		)
	)
)
